#ISCELL
  logical_power cad_note *
  *
#ISCELL
  mstr_misc dns *
  *
#ISCELL
  pure_quanta quanta_title_block_c *
  *
#ISCELL
  standard offpage *
  page213_i1
#ISCELL
  standard offpage *
  page213_i10
#ISCELL
  standard offpage *
  page213_i12
#ISCELL
  logical_power universal_gnd *
  page213_i17
#CELL
  pure_quanta q_res *
  page213_i18
#ISCELL
  logical_power universal_power *
  page213_i19
#CELL
  pure_quanta 74lvc2g17gw *
  page213_i2
#ISCELL
  logical_power universal_gnd *
  page213_i20
#CELL
  pure_quanta mosfet_nch_dual *
  page213_i21
#CELL
  pure_quanta q_res *
  page213_i22
#ISCELL
  logical_power universal_power *
  page213_i23
#CELL
  pure_quanta mosfet_nch_dual *
  page213_i27
#ISCELL
  standard offpage *
  page213_i28
#CELL
  pure_quanta q_res *
  page213_i29
#ISCELL
  logical_power universal_gnd *
  page213_i3
#ISCELL
  standard offpage *
  page213_i30
#ISCELL
  logical_power universal_power *
  page213_i31
#CELL
  pure_quanta q_res *
  page213_i32
#CELL
  pure_quanta q_res *
  page213_i33
#ISCELL
  logical_power universal_gnd *
  page213_i34
#CELL
  pure_quanta q_cap *
  page213_i35
#ISCELL
  logical_power universal_power *
  page213_i36
#CELL
  pure_quanta 74lvc2g07dw7 *
  page213_i37
#ISCELL
  logical_power universal_gnd *
  page213_i38
#ISCELL
  logical_power universal_power *
  page213_i39
#ISCELL
  logical_power universal_gnd *
  page213_i4
#CELL
  pure_quanta q_res *
  page213_i40
#CELL
  pure_quanta q_res *
  page213_i41
#CELL
  pure_quanta q_cap *
  page213_i42
#ISCELL
  logical_power universal_gnd *
  page213_i43
#ISCELL
  standard offpage *
  page213_i44
#CELL
  pure_quanta q_cap *
  page213_i5
#ISCELL
  logical_power universal_power *
  page213_i6
#CELL
  pure_quanta q_res *
  page213_i7
#ISCELL
  logical_power universal_power *
  page213_i8
